# S9S_MB_2U (Grand Teton) — schematic netlist excerpt (pin names and nets, part order shuffled) for the footprints in the layout excerpt that follows; sources: Cadence DE-HDL packaged netlist, KiCad conversion of 03242023_DA0F0TMBIJ0_F0T_Motherboard_J_brd_V01_OCP.brd

R4680  Q_RES  100K 1% CHIP  pkg 0402LF  page 260 : A = P12V_AUX ; B = PWRGD_P5V_N
PC534_P1_3  Q_CAP  22UF 16V 20% X6S  pkg C0805  page 286 : A = SW_P12V_PVCCIN_CPU1_FLT ; B = GND
R298  Q_RES  301 1% CHIP  pkg 0402LF  page 118 : A = PVNN_TERM_CPU1 ; B = H_CPU_CATERR_LVC1_R_N

(kicad_pcb
	(version 20260206)
	(generator "pcbnew")
	(generator_version "10.0")
	(general
		(thickness 1.6)
		(legacy_teardrops no)
	)
	(paper "A4")
	(title_block
		(title "03242023_DA0F0TMBIJ0_F0T_Motherboard_J_brd_V01_OCP.brd")
		(comment 1 "Grand Teton / footprints 5736-5738 of 6105")
	)
	(layers
		(0 "F.Cu" signal "TOP")
		(4 "In1.Cu" signal "GND")
		(6 "In2.Cu" signal "IN1")
		(8 "In3.Cu" signal "GND1")
		(10 "In4.Cu" signal "IN2")
		(12 "In5.Cu" signal "GND2")
		(14 "In6.Cu" signal "IN3")
		(16 "In7.Cu" signal "GND3")
		(18 "In8.Cu" signal "VCC")
		(20 "In9.Cu" signal "VCC1")
		(22 "In10.Cu" signal "GND4")
		(24 "In11.Cu" signal "IN4")
		(26 "In12.Cu" signal "GND5")
		(28 "In13.Cu" signal "IN5")
		(30 "In14.Cu" signal "GND6")
		(32 "In15.Cu" signal "IN6")
		(34 "In16.Cu" signal "GND7")
		(2 "B.Cu" signal "BOTTOM")
		(9 "F.Adhes" user "F.Adhesive")
		(11 "B.Adhes" user "B.Adhesive")
		(13 "F.Paste" user "Package Geometry/Pastemask Top")
		(15 "B.Paste" user "Package Geometry/Pastemask Bottom")
		(5 "F.SilkS" user "Ref Des/Silkscreen Top")
		(7 "B.SilkS" user "Ref Des/Silkscreen Bottom")
		(1 "F.Mask" user "Board Geometry/Soldermask Top")
		(3 "B.Mask" user "Board Geometry/Soldermask Bottom")
		(17 "Dwgs.User" user "User.Drawings")
		(19 "Cmts.User" user "User.Comments")
		(21 "Eco1.User" user "User.Eco1")
		(23 "Eco2.User" user "User.Eco2")
		(25 "Edge.Cuts" user "Board Geometry/Outline")
		(27 "Margin" user)
		(31 "F.CrtYd" user "Package Geometry/Place Bound Top")
		(29 "B.CrtYd" user "Package Geometry/Place Bound Bottom")
		(35 "F.Fab" user "Ref Des/Assembly Top")
		(33 "B.Fab" user "Ref Des/Assembly Bottom")
	)
	(footprint ""
		(layer "B.Cu")
		(at 433.21478 -50.72888 180)
		(property "Reference" "R4680"
			(at 0 0 0)
			(layer "B.SilkS")
			(hide yes)
			(effects
				(font
					(size 1.27 1.27)
				)
				(justify mirror)
			)
		)
		(property "Value" ""
			(at 0 0 0)
			(layer "B.Fab")
			(effects
				(font
					(size 1.27 1.27)
				)
				(justify mirror)
			)
		)
		(duplicate_pad_numbers_are_jumpers no)
		(fp_line
			(start 0.7874 0.4064)
			(end 0.7874 -0.4064)
			(stroke
				(width 0.1524)
				(type default)
			)
			(layer "B.SilkS")
		)
		(fp_line
			(start 0.7874 -0.4064)
			(end -0.7874 -0.4064)
			(stroke
				(width 0.1524)
				(type default)
			)
			(layer "B.SilkS")
		)
		(fp_line
			(start -0.7874 0.4064)
			(end 0.7874 0.4064)
			(stroke
				(width 0.1524)
				(type default)
			)
			(layer "B.SilkS")
		)
		(fp_line
			(start -0.7874 -0.4064)
			(end -0.7874 0.4064)
			(stroke
				(width 0.1524)
				(type default)
			)
			(layer "B.SilkS")
		)
		(fp_line
			(start 0.67945 0.3048)
			(end 0.67945 -0.305054)
			(stroke
				(width 0.1)
				(type default)
			)
			(layer "B.Fab")
		)
		(fp_line
			(start 0.67945 -0.305054)
			(end 0.12065 -0.305054)
			(stroke
				(width 0.1)
				(type default)
			)
			(layer "B.Fab")
		)
		(fp_line
			(start 0.12065 0.3048)
			(end 0.67945 0.3048)
			(stroke
				(width 0.1)
				(type default)
			)
			(layer "B.Fab")
		)
		(fp_line
			(start 0.12065 0.2794)
			(end 0.12065 0.3048)
			(stroke
				(width 0.1)
				(type default)
			)
			(layer "B.Fab")
		)
		(fp_line
			(start 0.12065 -0.2794)
			(end -0.12065 -0.2794)
			(stroke
				(width 0.1)
				(type default)
			)
			(layer "B.Fab")
		)
		(fp_line
			(start 0.12065 -0.305054)
			(end 0.12065 -0.2794)
			(stroke
				(width 0.1)
				(type default)
			)
			(layer "B.Fab")
		)
		(fp_line
			(start -0.120396 0.3048)
			(end -0.120396 0.2794)
			(stroke
				(width 0.1)
				(type default)
			)
			(layer "B.Fab")
		)
		(fp_line
			(start -0.120396 0.2794)
			(end 0.12065 0.2794)
			(stroke
				(width 0.1)
				(type default)
			)
			(layer "B.Fab")
		)
		(fp_line
			(start -0.12065 -0.2794)
			(end -0.12065 -0.3048)
			(stroke
				(width 0.1)
				(type default)
			)
			(layer "B.Fab")
		)
		(fp_line
			(start -0.12065 -0.3048)
			(end -0.67945 -0.3048)
			(stroke
				(width 0.1)
				(type default)
			)
			(layer "B.Fab")
		)
		(fp_line
			(start -0.67945 0.3048)
			(end -0.120396 0.3048)
			(stroke
				(width 0.1)
				(type default)
			)
			(layer "B.Fab")
		)
		(fp_line
			(start -0.67945 -0.3048)
			(end -0.67945 0.3048)
			(stroke
				(width 0.1)
				(type default)
			)
			(layer "B.Fab")
		)
		(pad "1" smd circle
			(at 0.40005 0)
			(size 0 0)
			(layers "B.Cu" "B.Mask" "B.Paste")
			(net "P12V_AUX")
		)
		(pad "2" smd circle
			(at -0.40005 0)
			(size 0 0)
			(layers "B.Cu" "B.Mask" "B.Paste")
			(net "PWRGD_P5V_N")
		)
	)
	(footprint ""
		(layer "B.Cu")
		(at 116.575586 -333.73568 90)
		(property "Reference" "PC534_P1_3"
			(at 0 0 90)
			(layer "B.SilkS")
			(hide yes)
			(effects
				(font
					(size 1.27 1.27)
				)
				(justify mirror)
			)
		)
		(property "Value" ""
			(at 0 0 90)
			(layer "B.Fab")
			(effects
				(font
					(size 1.27 1.27)
				)
				(justify mirror)
			)
		)
		(duplicate_pad_numbers_are_jumpers no)
		(fp_line
			(start 1.524 -0.762)
			(end -1.524 -0.762)
			(stroke
				(width 0.1524)
				(type default)
			)
			(layer "B.SilkS")
		)
		(fp_line
			(start -1.524 -0.762)
			(end -1.524 0.762)
			(stroke
				(width 0.1524)
				(type default)
			)
			(layer "B.SilkS")
		)
		(fp_line
			(start 1.524 0.762)
			(end 1.524 -0.762)
			(stroke
				(width 0.1524)
				(type default)
			)
			(layer "B.SilkS")
		)
		(fp_line
			(start -1.524 0.762)
			(end 1.524 0.762)
			(stroke
				(width 0.1524)
				(type default)
			)
			(layer "B.SilkS")
		)
		(fp_line
			(start 1.1049 -0.724916)
			(end 1.1049 0.724916)
			(stroke
				(width 0.1)
				(type default)
			)
			(layer "B.Fab")
		)
		(fp_line
			(start -1.1049 -0.724916)
			(end 1.1049 -0.724916)
			(stroke
				(width 0.1)
				(type default)
			)
			(layer "B.Fab")
		)
		(fp_line
			(start 1.1049 0.724916)
			(end -1.1049 0.724916)
			(stroke
				(width 0.1)
				(type default)
			)
			(layer "B.Fab")
		)
		(fp_line
			(start -1.1049 0.724916)
			(end -1.1049 -0.724916)
			(stroke
				(width 0.1)
				(type default)
			)
			(layer "B.Fab")
		)
		(pad "1" smd rect
			(at 0.889 0 90)
			(size 1.016 1.27)
			(layers "B.Cu" "B.Mask" "B.Paste")
			(net "SW_P12V_PVCCIN_CPU1_FLT")
		)
		(pad "2" smd rect
			(at -0.889 0 90)
			(size 1.016 1.27)
			(layers "B.Cu" "B.Mask" "B.Paste")
			(net "GND")
		)
	)
	(footprint ""
		(layer "B.Cu")
		(at 74.850498 -179.34178 -90)
		(property "Reference" "R298"
			(at 0 0 90)
			(layer "B.SilkS")
			(hide yes)
			(effects
				(font
					(size 1.27 1.27)
				)
				(justify mirror)
			)
		)
		(property "Value" ""
			(at 0 0 90)
			(layer "B.Fab")
			(effects
				(font
					(size 1.27 1.27)
				)
				(justify mirror)
			)
		)
		(duplicate_pad_numbers_are_jumpers no)
		(fp_line
			(start -0.7874 0.4064)
			(end 0.7874 0.4064)
			(stroke
				(width 0.1524)
				(type default)
			)
			(layer "B.SilkS")
		)
		(fp_line
			(start 0.7874 0.4064)
			(end 0.7874 -0.4064)
			(stroke
				(width 0.1524)
				(type default)
			)
			(layer "B.SilkS")
		)
		(fp_line
			(start -0.7874 -0.4064)
			(end -0.7874 0.4064)
			(stroke
				(width 0.1524)
				(type default)
			)
			(layer "B.SilkS")
		)
		(fp_line
			(start 0.7874 -0.4064)
			(end -0.7874 -0.4064)
			(stroke
				(width 0.1524)
				(type default)
			)
			(layer "B.SilkS")
		)
		(fp_line
			(start -0.67945 0.3048)
			(end -0.120396 0.3048)
			(stroke
				(width 0.1)
				(type default)
			)
			(layer "B.Fab")
		)
		(fp_line
			(start -0.120396 0.3048)
			(end -0.120396 0.2794)
			(stroke
				(width 0.1)
				(type default)
			)
			(layer "B.Fab")
		)
		(fp_line
			(start 0.12065 0.3048)
			(end 0.67945 0.3048)
			(stroke
				(width 0.1)
				(type default)
			)
			(layer "B.Fab")
		)
		(fp_line
			(start 0.67945 0.3048)
			(end 0.67945 -0.305054)
			(stroke
				(width 0.1)
				(type default)
			)
			(layer "B.Fab")
		)
		(fp_line
			(start -0.120396 0.2794)
			(end 0.12065 0.2794)
			(stroke
				(width 0.1)
				(type default)
			)
			(layer "B.Fab")
		)
		(fp_line
			(start 0.12065 0.2794)
			(end 0.12065 0.3048)
			(stroke
				(width 0.1)
				(type default)
			)
			(layer "B.Fab")
		)
		(fp_line
			(start -0.12065 -0.2794)
			(end -0.12065 -0.3048)
			(stroke
				(width 0.1)
				(type default)
			)
			(layer "B.Fab")
		)
		(fp_line
			(start 0.12065 -0.2794)
			(end -0.12065 -0.2794)
			(stroke
				(width 0.1)
				(type default)
			)
			(layer "B.Fab")
		)
		(fp_line
			(start -0.67945 -0.3048)
			(end -0.67945 0.3048)
			(stroke
				(width 0.1)
				(type default)
			)
			(layer "B.Fab")
		)
		(fp_line
			(start -0.12065 -0.3048)
			(end -0.67945 -0.3048)
			(stroke
				(width 0.1)
				(type default)
			)
			(layer "B.Fab")
		)
		(fp_line
			(start 0.12065 -0.305054)
			(end 0.12065 -0.2794)
			(stroke
				(width 0.1)
				(type default)
			)
			(layer "B.Fab")
		)
		(fp_line
			(start 0.67945 -0.305054)
			(end 0.12065 -0.305054)
			(stroke
				(width 0.1)
				(type default)
			)
			(layer "B.Fab")
		)
		(pad "1" smd circle
			(at 0.40005 0 90)
			(size 0 0)
			(layers "B.Cu" "B.Mask" "B.Paste")
			(net "PVNN_TERM_CPU1")
		)
		(pad "2" smd circle
			(at -0.40005 0 90)
			(size 0 0)
			(layers "B.Cu" "B.Mask" "B.Paste")
			(net "H_CPU_CATERR_LVC1_R_N")
		)
	)
)
